# TIMECARD (Time Appliance Project (Time Card)) — schematic netlist excerpt (pin names and nets, part order shuffled) for the footprints in the layout excerpt that follows; sources: Cadence DE-HDL packaged netlist, KiCad conversion of R4006-B0001-02_R01.brd

C116  CAPACITOR  0.1UF 10V 10%  pkg SMC_0402R_H022  page 14 : \1\ = XP2R5V_FPGA ; \2\ = SG
FU3  FUSE  1A  pkg SMC_0603R_H024  page 21 : \1\ = UNNAMED_527_FUSE_I244_1 ; \2\ = XP5R0V_MAC_USB

(kicad_pcb
	(version 20260206)
	(generator "pcbnew")
	(generator_version "10.0")
	(general
		(thickness 1.6)
		(legacy_teardrops no)
	)
	(paper "A4")
	(title_block
		(title "timecard-production-celestica-r4006 — R4006-B0001-02_R01.brd")
		(comment 1 "Time Appliance Project (Time Card) / footprints 763-764 of 1113")
	)
	(layers
		(0 "F.Cu" signal "TOP")
		(4 "In1.Cu" signal "L02_GND1")
		(6 "In2.Cu" signal "L03_SIG1")
		(8 "In3.Cu" signal "L04_GND2")
		(10 "In4.Cu" signal "L05_VCC1")
		(12 "In5.Cu" signal "L06_VCC2")
		(14 "In6.Cu" signal "L07_GND3")
		(16 "In7.Cu" signal "L08_SIG2")
		(18 "In8.Cu" signal "L09_GND4")
		(2 "B.Cu" signal "BOTTOM")
		(9 "F.Adhes" user "F.Adhesive")
		(11 "B.Adhes" user "B.Adhesive")
		(13 "F.Paste" user "Package Geometry/Pastemask Top")
		(15 "B.Paste" user "Package Geometry/Pastemask Bottom")
		(5 "F.SilkS" user "Ref Des/Silkscreen Top")
		(7 "B.SilkS" user "Ref Des/Silkscreen Bottom")
		(1 "F.Mask" user "Board Geometry/Soldermask Top")
		(3 "B.Mask" user "Board Geometry/Soldermask Bottom")
		(17 "Dwgs.User" user "User.Drawings")
		(19 "Cmts.User" user "User.Comments")
		(21 "Eco1.User" user "User.Eco1")
		(23 "Eco2.User" user "User.Eco2")
		(25 "Edge.Cuts" user "Board Geometry/Outline")
		(27 "Margin" user)
		(31 "F.CrtYd" user "Package Geometry/Place Bound Top")
		(29 "B.CrtYd" user "Package Geometry/Place Bound Bottom")
		(35 "F.Fab" user "Ref Des/Assembly Top")
		(33 "B.Fab" user "Ref Des/Assembly Bottom")
	)
	(footprint ""
		(layer "B.Cu")
		(at 72.263 -55.753 90)
		(property "Reference" "FU3"
			(at -2.413 0.08763 270)
			(unlocked yes)
			(layer "B.SilkS")
			(effects
				(font
					(size 0.7874 0.5842)
					(thickness 0.1524)
				)
				(justify mirror)
			)
		)
		(property "Value" "VAL*"
			(at 0.0254 2.524506 90)
			(unlocked yes)
			(layer "B.Fab")
			(hide yes)
			(effects
				(font
					(size 0.7874 0.5842)
					(thickness 0.1524)
				)
				(justify mirror)
			)
		)
		(property "Tolerance" "TOL*"
			(at 0.0254 3.464306 90)
			(unlocked yes)
			(layer "Cmts.User")
			(hide yes)
			(effects
				(font
					(size 0.7874 0.5842)
					(thickness 0.1524)
				)
				(justify mirror)
			)
		)
		(property "User Part Number" "PARTNUM*"
			(at 0.0254 4.505706 90)
			(unlocked yes)
			(layer "Cmts.User")
			(hide yes)
			(effects
				(font
					(size 0.7874 0.5842)
					(thickness 0.1524)
				)
				(justify mirror)
			)
		)
		(property "Device Type" "FUSE-G280-10049-01,1A"
			(at 0 1.610106 90)
			(unlocked yes)
			(layer "B.Fab")
			(hide yes)
			(effects
				(font
					(size 0.7874 0.5842)
					(thickness 0.1524)
				)
				(justify mirror)
			)
		)
		(duplicate_pad_numbers_are_jumpers no)
		(fp_line
			(start 1.3208 -0.7112)
			(end -1.3208 -0.7112)
			(stroke
				(width 0.1)
				(type default)
			)
			(layer "B.SilkS")
		)
		(fp_line
			(start -1.3208 -0.7112)
			(end -1.3208 0.7112)
			(stroke
				(width 0.1)
				(type default)
			)
			(layer "B.SilkS")
		)
		(fp_line
			(start 1.3208 0.7112)
			(end 1.3208 -0.7112)
			(stroke
				(width 0.1)
				(type default)
			)
			(layer "B.SilkS")
		)
		(fp_line
			(start -1.3208 0.7112)
			(end 1.3208 0.7112)
			(stroke
				(width 0.1)
				(type default)
			)
			(layer "B.SilkS")
		)
		(fp_rect
			(start 1.3208 0.7112)
			(end -1.3208 -0.7112)
			(stroke
				(width 0)
				(type default)
			)
			(fill no)
			(layer "B.CrtYd")
		)
		(fp_line
			(start 0.8128 -0.4572)
			(end -0.8128 -0.4572)
			(stroke
				(width 0.1)
				(type default)
			)
			(layer "B.Fab")
		)
		(fp_line
			(start -0.8128 -0.4572)
			(end -0.8128 0.4572)
			(stroke
				(width 0.1)
				(type default)
			)
			(layer "B.Fab")
		)
		(fp_line
			(start 0.8128 0.4572)
			(end 0.8128 -0.4572)
			(stroke
				(width 0.1)
				(type default)
			)
			(layer "B.Fab")
		)
		(fp_line
			(start -0.8128 0.4572)
			(end 0.8128 0.4572)
			(stroke
				(width 0.1)
				(type default)
			)
			(layer "B.Fab")
		)
		(pad "1" smd rect
			(at 0.6858 0 270)
			(size 0.762 0.8636)
			(layers "B.Cu" "B.Mask" "B.Paste")
			(net "UNNAMED_527_FUSE_I244_1")
		)
		(pad "2" smd rect
			(at -0.6858 0 270)
			(size 0.762 0.8636)
			(layers "B.Cu" "B.Mask" "B.Paste")
			(net "XP5R0V_MAC_USB")
		)
		(zone
			(layer "B.Cu")
			(hatch none 0.5)
			(connect_pads
				(clearance 0)
			)
			(min_thickness 0.25)
			(keepout
				(tracks not_allowed)
				(vias allowed)
				(pads allowed)
				(copperpour not_allowed)
				(footprints allowed)
			)
			(placement
				(enabled no)
				(sheetname "")
			)
			(fill
				(thermal_gap 0.5)
				(thermal_bridge_width 0.5)
				(island_removal_mode 0)
			)
			(polygon
				(pts
					(xy 72.7202 -55.9054) (xy 71.8058 -55.9054) (xy 71.8058 -55.6006) (xy 72.7202 -55.6006)
				)
			)
		)
		(zone
			(layer "B.Cu")
			(hatch none 0.5)
			(connect_pads
				(clearance 0)
			)
			(min_thickness 0.25)
			(keepout
				(tracks allowed)
				(vias not_allowed)
				(pads allowed)
				(copperpour not_allowed)
				(footprints allowed)
			)
			(placement
				(enabled no)
				(sheetname "")
			)
			(fill
				(thermal_gap 0.5)
				(thermal_bridge_width 0.5)
				(island_removal_mode 0)
			)
			(polygon
				(pts
					(xy 72.7202 -55.9054) (xy 71.8058 -55.9054) (xy 71.8058 -55.6006) (xy 72.7202 -55.6006)
				)
			)
		)
	)
	(footprint ""
		(layer "B.Cu")
		(at 98.991166 -32.857694)
		(property "Reference" "C116"
			(at 2.989834 0.258064 0)
			(unlocked yes)
			(layer "B.SilkS")
			(effects
				(font
					(size 0.7874 0.5842)
					(thickness 0.1524)
				)
				(justify mirror)
			)
		)
		(property "Value" "VAL*"
			(at -0.0762 2.067306 0)
			(unlocked yes)
			(layer "B.Fab")
			(hide yes)
			(effects
				(font
					(size 0.7874 0.5842)
					(thickness 0.1524)
				)
				(justify mirror)
			)
		)
		(property "Tolerance" "TOL*"
			(at -0.0762 3.032506 0)
			(unlocked yes)
			(layer "Cmts.User")
			(hide yes)
			(effects
				(font
					(size 0.7874 0.5842)
					(thickness 0.1524)
				)
				(justify mirror)
			)
		)
		(property "User Part Number" "PARTNUM*"
			(at -0.1016 4.023106 0)
			(unlocked yes)
			(layer "Cmts.User")
			(hide yes)
			(effects
				(font
					(size 0.7874 0.5842)
					(thickness 0.1524)
				)
				(justify mirror)
			)
		)
		(property "Device Type" "CAPACITOR-G105-0B104-CK,0.1UF,A"
			(at -0.0508 1.127506 0)
			(unlocked yes)
			(layer "B.Fab")
			(hide yes)
			(effects
				(font
					(size 0.7874 0.5842)
					(thickness 0.1524)
				)
				(justify mirror)
			)
		)
		(duplicate_pad_numbers_are_jumpers no)
		(fp_line
			(start -1.143 -0.5588)
			(end 1.143 -0.5588)
			(stroke
				(width 0.1)
				(type default)
			)
			(layer "B.SilkS")
		)
		(fp_line
			(start -1.143 0.5588)
			(end -1.143 -0.5588)
			(stroke
				(width 0.1)
				(type default)
			)
			(layer "B.SilkS")
		)
		(fp_line
			(start 1.143 -0.5588)
			(end 1.143 0.5588)
			(stroke
				(width 0.1)
				(type default)
			)
			(layer "B.SilkS")
		)
		(fp_line
			(start 1.143 0.5588)
			(end -1.143 0.5588)
			(stroke
				(width 0.1)
				(type default)
			)
			(layer "B.SilkS")
		)
		(fp_poly
			(pts
				(xy 1.143 0.5588) (xy -1.143 0.5588) (xy -1.143 -0.5588) (xy 1.143 -0.5588)
			)
			(stroke
				(width 0)
				(type default)
			)
			(fill no)
			(layer "B.CrtYd")
		)
		(fp_line
			(start -0.508 -0.3048)
			(end 0.508 -0.3048)
			(stroke
				(width 0.1)
				(type default)
			)
			(layer "B.Fab")
		)
		(fp_line
			(start -0.508 0.3048)
			(end -0.508 -0.3048)
			(stroke
				(width 0.1)
				(type default)
			)
			(layer "B.Fab")
		)
		(fp_line
			(start 0.508 -0.3048)
			(end 0.508 0.3048)
			(stroke
				(width 0.1)
				(type default)
			)
			(layer "B.Fab")
		)
		(fp_line
			(start 0.508 0.3048)
			(end -0.508 0.3048)
			(stroke
				(width 0.1)
				(type default)
			)
			(layer "B.Fab")
		)
		(pad "1" smd rect
			(at 0.5334 0 180)
			(size 0.7112 0.6096)
			(layers "B.Cu" "B.Mask" "B.Paste")
			(net "XP2R5V_FPGA")
		)
		(pad "2" smd rect
			(at -0.5334 0 180)
			(size 0.7112 0.6096)
			(layers "B.Cu" "B.Mask" "B.Paste")
			(net "SG")
		)
		(zone
			(layer "B.Cu")
			(hatch none 0.5)
			(connect_pads
				(clearance 0)
			)
			(min_thickness 0.25)
			(keepout
				(tracks allowed)
				(vias not_allowed)
				(pads allowed)
				(copperpour not_allowed)
				(footprints allowed)
			)
			(placement
				(enabled no)
				(sheetname "")
			)
			(fill
				(thermal_gap 0.5)
				(thermal_bridge_width 0.5)
				(island_removal_mode 0)
			)
			(polygon
				(pts
					(xy 99.067366 -32.552894) (xy 99.067366 -33.162494) (xy 98.914966 -33.162494) (xy 98.914966 -32.552894)
				)
			)
		)
		(zone
			(layer "B.Cu")
			(hatch none 0.5)
			(connect_pads
				(clearance 0)
			)
			(min_thickness 0.25)
			(keepout
				(tracks not_allowed)
				(vias allowed)
				(pads allowed)
				(copperpour not_allowed)
				(footprints allowed)
			)
			(placement
				(enabled no)
				(sheetname "")
			)
			(fill
				(thermal_gap 0.5)
				(thermal_bridge_width 0.5)
				(island_removal_mode 0)
			)
			(polygon
				(pts
					(xy 99.067366 -32.552894) (xy 99.067366 -33.162494) (xy 98.914966 -33.162494) (xy 98.914966 -32.552894)
				)
			)
		)
	)
)
